# T6G (Grand Teton) — schematic netlist excerpt (pin names and nets, part order shuffled) for the footprints in the layout excerpt that follows; sources: Cadence DE-HDL packaged netlist, KiCad conversion of 04192023_DAF0TMB3IC0_F0TG_MB_C_brd_V02_OCP.brd

R2671  Q_RES  33.2 1% CHIP  pkg 0402LF  page 248 : A = SMB_BMC_SWB_BUF_R_SCL ; B = SMB_BMC_SWB_BUF_SCL

PL17  Q_INDUCTOR4P_14  150NH IND  pkg L_TLM117513Q-151QL_11X7-5XA  page 205
  \1\  = SW_PVDDIO_P0_SW1
  \2\  = IND_PVDDIO_P0_CPL2
  \3\  = GND
  \4\  = PVDDIO_P0

(kicad_pcb
	(version 20260206)
	(generator "pcbnew")
	(generator_version "10.0")
	(general
		(thickness 1.6)
		(legacy_teardrops no)
	)
	(paper "A4")
	(title_block
		(title "04192023_DAF0TMB3IC0_F0TG_MB_C_brd_V02_OCP.brd")
		(comment 1 "Grand Teton / footprints 1700-1701 of 8354")
	)
	(layers
		(0 "F.Cu" signal "TOP")
		(4 "In1.Cu" signal "GND")
		(6 "In2.Cu" signal "IN1")
		(8 "In3.Cu" signal "GND1")
		(10 "In4.Cu" signal "IN2")
		(12 "In5.Cu" signal "GND2")
		(14 "In6.Cu" signal "IN3")
		(16 "In7.Cu" signal "GND3")
		(18 "In8.Cu" signal "VCC")
		(20 "In9.Cu" signal "VCC1")
		(22 "In10.Cu" signal "GND4")
		(24 "In11.Cu" signal "IN4")
		(26 "In12.Cu" signal "GND5")
		(28 "In13.Cu" signal "IN5")
		(30 "In14.Cu" signal "GND6")
		(32 "In15.Cu" signal "IN6")
		(34 "In16.Cu" signal "GND7")
		(2 "B.Cu" signal "BOTTOM")
		(9 "F.Adhes" user "F.Adhesive")
		(11 "B.Adhes" user "B.Adhesive")
		(13 "F.Paste" user "Package Geometry/Pastemask Top")
		(15 "B.Paste" user "Package Geometry/Pastemask Bottom")
		(5 "F.SilkS" user "Ref Des/Silkscreen Top")
		(7 "B.SilkS" user "Ref Des/Silkscreen Bottom")
		(1 "F.Mask" user "Board Geometry/Soldermask Top")
		(3 "B.Mask" user "Board Geometry/Soldermask Bottom")
		(17 "Dwgs.User" user "User.Drawings")
		(19 "Cmts.User" user "User.Comments")
		(21 "Eco1.User" user "User.Eco1")
		(23 "Eco2.User" user "User.Eco2")
		(25 "Edge.Cuts" user "Board Geometry/Outline")
		(27 "Margin" user)
		(31 "F.CrtYd" user "Package Geometry/Place Bound Top")
		(29 "B.CrtYd" user "Package Geometry/Place Bound Bottom")
		(35 "F.Fab" user "Ref Des/Assembly Top")
		(33 "B.Fab" user "Ref Des/Assembly Bottom")
	)
	(footprint ""
		(layer "F.Cu")
		(at 166.3192 -431.3936)
		(property "Reference" "R2671"
			(at 0 0 0)
			(layer "F.SilkS")
			(hide yes)
			(effects
				(font
					(size 1.27 1.27)
				)
			)
		)
		(property "Value" ""
			(at 0 0 0)
			(layer "F.Fab")
			(effects
				(font
					(size 1.27 1.27)
				)
			)
		)
		(duplicate_pad_numbers_are_jumpers no)
		(fp_line
			(start -0.7874 -0.4064)
			(end 0.7874 -0.4064)
			(stroke
				(width 0.1524)
				(type default)
			)
			(layer "F.SilkS")
		)
		(fp_line
			(start -0.7874 0.4064)
			(end -0.7874 -0.4064)
			(stroke
				(width 0.1524)
				(type default)
			)
			(layer "F.SilkS")
		)
		(fp_line
			(start 0.7874 -0.4064)
			(end 0.7874 0.4064)
			(stroke
				(width 0.1524)
				(type default)
			)
			(layer "F.SilkS")
		)
		(fp_line
			(start 0.7874 0.4064)
			(end -0.7874 0.4064)
			(stroke
				(width 0.1524)
				(type default)
			)
			(layer "F.SilkS")
		)
		(fp_line
			(start -0.67945 -0.305054)
			(end -0.12065 -0.305054)
			(stroke
				(width 0.1)
				(type default)
			)
			(layer "F.Fab")
		)
		(fp_line
			(start -0.67945 0.3048)
			(end -0.67945 -0.305054)
			(stroke
				(width 0.1)
				(type default)
			)
			(layer "F.Fab")
		)
		(fp_line
			(start -0.12065 -0.305054)
			(end -0.12065 -0.2794)
			(stroke
				(width 0.1)
				(type default)
			)
			(layer "F.Fab")
		)
		(fp_line
			(start -0.12065 -0.2794)
			(end 0.12065 -0.2794)
			(stroke
				(width 0.1)
				(type default)
			)
			(layer "F.Fab")
		)
		(fp_line
			(start -0.12065 0.2794)
			(end -0.12065 0.3048)
			(stroke
				(width 0.1)
				(type default)
			)
			(layer "F.Fab")
		)
		(fp_line
			(start -0.12065 0.3048)
			(end -0.67945 0.3048)
			(stroke
				(width 0.1)
				(type default)
			)
			(layer "F.Fab")
		)
		(fp_line
			(start 0.120396 0.2794)
			(end -0.12065 0.2794)
			(stroke
				(width 0.1)
				(type default)
			)
			(layer "F.Fab")
		)
		(fp_line
			(start 0.120396 0.3048)
			(end 0.120396 0.2794)
			(stroke
				(width 0.1)
				(type default)
			)
			(layer "F.Fab")
		)
		(fp_line
			(start 0.12065 -0.3048)
			(end 0.67945 -0.3048)
			(stroke
				(width 0.1)
				(type default)
			)
			(layer "F.Fab")
		)
		(fp_line
			(start 0.12065 -0.2794)
			(end 0.12065 -0.3048)
			(stroke
				(width 0.1)
				(type default)
			)
			(layer "F.Fab")
		)
		(fp_line
			(start 0.67945 -0.3048)
			(end 0.67945 0.3048)
			(stroke
				(width 0.1)
				(type default)
			)
			(layer "F.Fab")
		)
		(fp_line
			(start 0.67945 0.3048)
			(end 0.120396 0.3048)
			(stroke
				(width 0.1)
				(type default)
			)
			(layer "F.Fab")
		)
		(pad "1" smd circle
			(at -0.40005 0)
			(size 0 0)
			(layers "F.Cu" "F.Mask" "F.Paste")
			(net "SMB_BMC_SWB_BUF_R_SCL")
		)
		(pad "2" smd circle
			(at 0.40005 0)
			(size 0 0)
			(layers "F.Cu" "F.Mask" "F.Paste")
			(net "SMB_BMC_SWB_BUF_SCL")
		)
	)
	(footprint ""
		(layer "F.Cu")
		(at 300.482762 -337.399122)
		(property "Reference" "PL17"
			(at -3.242056 -15.760446 0)
			(unlocked yes)
			(layer "F.SilkS")
			(effects
				(font
					(size 0.7874 0.5842)
					(thickness 0.1524)
				)
				(justify left)
			)
		)
		(property "Value" ""
			(at 0 0 0)
			(layer "F.Fab")
			(effects
				(font
					(size 1.27 1.27)
				)
			)
		)
		(duplicate_pad_numbers_are_jumpers no)
		(fp_line
			(start -3.750056 -5.500116)
			(end -2.393442 -5.500116)
			(stroke
				(width 0.1524)
				(type default)
			)
			(layer "F.SilkS")
		)
		(fp_line
			(start -3.750056 5.500116)
			(end -3.750056 -5.500116)
			(stroke
				(width 0.1524)
				(type default)
			)
			(layer "F.SilkS")
		)
		(fp_line
			(start -2.393442 5.500116)
			(end -3.750056 5.500116)
			(stroke
				(width 0.1524)
				(type default)
			)
			(layer "F.SilkS")
		)
		(fp_line
			(start 2.393442 5.500116)
			(end 3.750056 5.500116)
			(stroke
				(width 0.1524)
				(type default)
			)
			(layer "F.SilkS")
		)
		(fp_line
			(start 3.750056 -5.500116)
			(end 2.393442 -5.500116)
			(stroke
				(width 0.1524)
				(type default)
			)
			(layer "F.SilkS")
		)
		(fp_line
			(start 3.750056 5.500116)
			(end 3.750056 -5.500116)
			(stroke
				(width 0.1524)
				(type default)
			)
			(layer "F.SilkS")
		)
		(fp_poly
			(pts
				(xy -3.9116 -4.249928) (xy -4.3434 -4.034028) (xy -4.3434 -4.465828)
			)
			(stroke
				(width 0)
				(type default)
			)
			(fill yes)
			(layer "F.SilkS")
		)
		(fp_line
			(start -3.750056 -5.500116)
			(end -3.750056 5.500116)
			(stroke
				(width 0.1)
				(type default)
			)
			(layer "F.Fab")
		)
		(fp_line
			(start -3.750056 5.500116)
			(end 3.750056 5.500116)
			(stroke
				(width 0.1)
				(type default)
			)
			(layer "F.Fab")
		)
		(fp_line
			(start 3.750056 -5.500116)
			(end -3.750056 -5.500116)
			(stroke
				(width 0.1)
				(type default)
			)
			(layer "F.Fab")
		)
		(fp_line
			(start 3.750056 5.500116)
			(end 3.750056 -5.500116)
			(stroke
				(width 0.1)
				(type default)
			)
			(layer "F.Fab")
		)
		(fp_poly
			(pts
				(xy -4.9276 -4.757928) (xy -4.9276 -3.741928) (xy -3.9116 -4.249928)
			)
			(stroke
				(width 0)
				(type default)
			)
			(fill yes)
			(layer "F.Fab")
		)
		(pad "1" smd rect
			(at 0 -4.249928 270)
			(size 2.413 4.5212)
			(layers "F.Cu" "F.Mask" "F.Paste")
			(net "SW_PVDDIO_P0_SW1")
		)
		(pad "2" smd rect
			(at 0 -1.175004 270)
			(size 1.3716 4.5212)
			(layers "F.Cu" "F.Mask" "F.Paste")
			(net "IND_PVDDIO_P0_CPL2")
		)
		(pad "3" smd rect
			(at 0 1.175004 270)
			(size 1.3716 4.5212)
			(layers "F.Cu" "F.Mask" "F.Paste")
			(net "GND")
		)
		(pad "4" smd rect
			(at 0 4.249928 270)
			(size 2.413 4.5212)
			(layers "F.Cu" "F.Mask" "F.Paste")
			(net "PVDDIO_P0")
		)
	)
)
